# S9S_MB_2U (Grand Teton) — schematic netlist excerpt (pin names and nets, part order shuffled) for the footprints in the layout excerpt that follows; sources: Cadence DE-HDL packaged netlist, KiCad conversion of 03242023_DA0F0TMBIJ0_F0T_Motherboard_J_brd_V01_OCP.brd

J8  SCONN288_ADR50017P087CC  SCONN288_ADR50017-P087CC IO  pkg DDR288S_1-1VXB  page 89
  VIN_BULK0  = P12V_S3_AUX_CPU0_NVDIMM
  RFU0  = TP_CHD_CPU0_DIMM2_FRU_0
  VIN_MGMT  = P3V3_AUX
  HSCL  = I3C_SPD_DDRABCD_CPU0_LVC1_SCL_7
  HSDA  = I3C_SPD_DDRABCD_CPU0_LVC1_SDA
  VSS0  = GND
  DQ0_A  = M_D_CPU0_SA_DQ<0>
  VSS1  = GND
  DQ1_A  = M_D_CPU0_SA_DQ<1>
  VSS2  = GND
  DQS0_A_T  = M_D_CPU0_SA_DQS_DP<0>
  DQS0_A_C  = M_D_CPU0_SA_DQS_DN<0>
  VSS3  = GND
  DQ4_A  = M_D_CPU0_SA_DQ<4>
  VSS4  = GND
  DQ5_A  = M_D_CPU0_SA_DQ<5>
  VSS5  = GND
  DQ8_A  = M_D_CPU0_SA_DQ<8>
  VSS6  = GND
  DQ9_A  = M_D_CPU0_SA_DQ<9>
  VSS7  = GND
  DQS1_A_T  = M_D_CPU0_SA_DQS_DP<1>
  DQS1_A_C  = M_D_CPU0_SA_DQS_DN<1>
  VSS8  = GND
  DQ12_A  = M_D_CPU0_SA_DQ<12>
  VSS9  = GND
  DQ13_A  = M_D_CPU0_SA_DQ<13>
  VSS10  = GND
  DQ16_A  = M_D_CPU0_SA_DQ<16>
  VSS11  = GND
  DQ17_A  = M_D_CPU0_SA_DQ<17>
  VSS12  = GND
  DQS2_A_T  = M_D_CPU0_SA_DQS_DP<2>
  DQS2_A_C  = M_D_CPU0_SA_DQS_DN<2>
  VSS13  = GND
  DQ20_A  = M_D_CPU0_SA_DQ<20>
  VSS14  = GND
  DQ21_A  = M_D_CPU0_SA_DQ<21>
  VSS15  = GND
  DQ24_A  = M_D_CPU0_SA_DQ<24>
  VSS16  = GND
  DQ25_A  = M_D_CPU0_SA_DQ<25>
  VSS17  = GND
  DQS3_A_T  = M_D_CPU0_SA_DQS_DP<3>
  DQS3_A_C  = M_D_CPU0_SA_DQS_DN<3>
  VSS18  = GND
  DQ28_A  = M_D_CPU0_SA_DQ<28>
  VSS19  = GND
  DQ29_A  = M_D_CPU0_SA_DQ<29>
  VSS20  = GND
  CB0_A  = M_D_CPU0_SA_CB<0>
  VSS21  = GND
  CB1_A  = M_D_CPU0_SA_CB<1>
  VSS22  = GND
  DQS4_A_T  = M_D_CPU0_SA_DQS_DP<4>
  DQS4_A_C  = M_D_CPU0_SA_DQS_DN<4>
  VSS23  = GND
  CB4_A  = M_D_CPU0_SA_CB<4>
  VSS24  = GND
  CB5_A  = M_D_CPU0_SA_CB<5>
  VSS25  = GND
  ALERT_N  = M_D_CPU0_ALERT_N
  VSS26  = GND
  CS0_A_N  = M_D_CPU0_SA_CS_N<2>
  VSS27  = GND
  CA0_A  = M_D_CPU0_SA_CA<0>
  VSS28  = GND
  CA2_A  = M_D_CPU0_SA_CA<2>
  VSS29  = GND
  CA4_A  = M_D_CPU0_SA_CA<4>
  VSS30  = GND
  CA6_A  = M_D_CPU0_SA_CA<6>
  VSS31  = GND
  PAR_A  = M_D_CPU0_SA_PAR
  VSS32  = GND
  CA0_B  = M_D_CPU0_SB_CA<0>
  VSS33  = GND
  CA2_B  = M_D_CPU0_SB_CA<2>
  VSS34  = GND
  CA4_B  = M_D_CPU0_SB_CA<4>
  VSS35  = GND
  CA6_B  = M_D_CPU0_SB_CA<6>
  VSS36  = GND
  CS0_B_N  = M_D_CPU0_SB_CS_N<2>
  VSS37  = GND
  \lbd||rsp_a_n\  = M_D_CPU0_SA_RSP<1>
  \lbs||rsp_b_n\  = M_D_CPU0_SB_RSP<1>
  VSS38  = GND
  CB4_B  = M_D_CPU0_SB_CB<4>
  VSS39  = GND
  CB5_B  = M_D_CPU0_SB_CB<5>
  VSS40  = GND
  \dqs9_b_t||tdqs9_b_t||dbi4_b_n\  = M_D_CPU0_SB_DQS_DP<9>
  \dqs9_b_c||tdqs9_b_c\  = M_D_CPU0_SB_DQS_DN<9>
  VSS41  = GND
  CB0_B  = M_D_CPU0_SB_CB<0>
  VSS42  = GND
  CB1_B  = M_D_CPU0_SB_CB<1>
  VSS43  = GND
  DQ0_B  = M_D_CPU0_SB_DQ<0>
  VSS44  = GND
  DQ1_B  = M_D_CPU0_SB_DQ<1>
  VSS45  = GND
  DQS0_B_T  = M_D_CPU0_SB_DQS_DP<0>
  DQS0_B_C  = M_D_CPU0_SB_DQS_DN<0>
  VSS46  = GND
  DQ4_B  = M_D_CPU0_SB_DQ<4>
  VSS47  = GND
  DQ5_B  = M_D_CPU0_SB_DQ<5>
  VSS48  = GND
  DQ8_B  = M_D_CPU0_SB_DQ<8>
  VSS49  = GND
  DQ9_B  = M_D_CPU0_SB_DQ<9>
  VSS50  = GND
  DQS1_B_T  = M_D_CPU0_SB_DQS_DP<1>
  DQS1_B_C  = M_D_CPU0_SB_DQS_DN<1>
  VSS51  = GND
  DQ12_B  = M_D_CPU0_SB_DQ<12>
  VSS52  = GND
  DQ13_B  = M_D_CPU0_SB_DQ<13>
  VSS53  = GND
  DQ16_B  = M_D_CPU0_SB_DQ<16>
  VSS54  = GND
  DQ17_B  = M_D_CPU0_SB_DQ<17>
  VSS55  = GND
  DQS2_B_T  = M_D_CPU0_SB_DQS_DP<2>
  DQS2_B_C  = M_D_CPU0_SB_DQS_DN<2>
  VSS56  = GND
  DQ20_B  = M_D_CPU0_SB_DQ<20>
  VSS57  = GND
  DQ21_B  = M_D_CPU0_SB_DQ<21>
  VSS58  = GND
  DQ24_B  = M_D_CPU0_SB_DQ<24>
  VSS59  = GND
  DQ25_B  = M_D_CPU0_SB_DQ<25>
  VSS60  = GND
  DQS3_B_T  = M_D_CPU0_SB_DQS_DP<3>
  DQS3_B_C  = M_D_CPU0_SB_DQS_DN<3>
  VSS61  = GND
  DQ28_B  = M_D_CPU0_SB_DQ<28>
  VSS62  = GND
  DQ29_B  = M_D_CPU0_SB_DQ<29>
  VSS63  = GND
  RFU1  = TP_CHD_CPU0_DIMM2_FRU_1
  VIN_BULK1  = P12V_S3_AUX_CPU0_NVDIMM
  VIN_BULK2  = P12V_S3_AUX_CPU0_NVDIMM
  \pwr_good||fail_n\  = PWRGD_CHD_CPU0_DIMM2
  HSA  = PD_CHD_CPU0_DIMM2_SAA
  RFU2  = TP_CHD_CPU0_DIMM2_FRU_2
  RFU3  = TP_CHD_CPU0_DIMM2_FRU_3
  VSS64  = GND
  DQ2_A  = M_D_CPU0_SA_DQ<2>
  VSS65  = GND
  DQ3_A  = M_D_CPU0_SA_DQ<3>
  VSS66  = GND
  \dqs5_a_c||tdqs5_a_c||dqs5_a_t||tdqs5_a_t\  = M_D_CPU0_SA_DQS_DN<5>
  \dqs5_a_t||tdqs5_a_t\  = M_D_CPU0_SA_DQS_DP<5>
  VSS67  = GND
  DQ6_A  = M_D_CPU0_SA_DQ<6>
  VSS68  = GND
  DQ7_A  = M_D_CPU0_SA_DQ<7>
  VSS69  = GND
  DQ10_A  = M_D_CPU0_SA_DQ<10>
  VSS70  = GND
  DQ11_A  = M_D_CPU0_SA_DQ<11>
  VSS71  = GND
  \dqs6_a_c||tdqs6_a_c||dqs6_a_t||tdqs6_a_t\  = M_D_CPU0_SA_DQS_DN<6>
  \dqs6_a_t||tdqs6_a_t\  = M_D_CPU0_SA_DQS_DP<6>
  VSS72  = GND
  DQ14_A  = M_D_CPU0_SA_DQ<14>
  VSS73  = GND
  DQ15_A  = M_D_CPU0_SA_DQ<15>
  VSS74  = GND
  DQ18_A  = M_D_CPU0_SA_DQ<18>
  VSS75  = GND
  DQ19_A  = M_D_CPU0_SA_DQ<19>
  VSS76  = GND
  \dqs7_a_c||tdqs7_a_c\  = M_D_CPU0_SA_DQS_DN<7>
  \dqs7_a_t||tdqs7_a_t\  = M_D_CPU0_SA_DQS_DP<7>
  VSS77  = GND
  DQ22_A  = M_D_CPU0_SA_DQ<22>
  VSS78  = GND
  DQ23_A  = M_D_CPU0_SA_DQ<23>
  VSS79  = GND
  DQ26_A  = M_D_CPU0_SA_DQ<26>
  VSS80  = GND
  DQ27_A  = M_D_CPU0_SA_DQ<27>
  VSS81  = GND
  \dqs8_a_c||tdqs8_a_c\  = M_D_CPU0_SA_DQS_DN<8>
  \dqs8_a_t||tdqs8_a_t\  = M_D_CPU0_SA_DQS_DP<8>
  VSS82  = GND
  DQ30_A  = M_D_CPU0_SA_DQ<30>
  VSS83  = GND
  DQ31_A  = M_D_CPU0_SA_DQ<31>
  VSS84  = GND
  CB2_A  = M_D_CPU0_SA_CB<2>
  VSS85  = GND
  CB3_A  = M_D_CPU0_SA_CB<3>
  VSS86  = GND
  \dqs9_a_c||tdqs9_a_c\  = M_D_CPU0_SA_DQS_DN<9>
  \dqs9_a_t||tdqs9_a_t\  = M_D_CPU0_SA_DQS_DP<9>
  VSS87  = GND
  CB6_A  = M_D_CPU0_SA_CB<6>
  VSS88  = GND
  CB7_A  = M_D_CPU0_SA_CB<7>
  VSS89  = GND
  RESET_N  = RST_M_CD_CPU0_FPGA_N
  VSS90  = GND
  CS1_A_N  = M_D_CPU0_SA_CS_N<3>
  VSS91  = GND
  CA1_A  = M_D_CPU0_SA_CA<1>
  VSS92  = GND
  CA3_A  = M_D_CPU0_SA_CA<3>
  VSS93  = GND
  CA5_A  = M_D_CPU0_SA_CA<5>
  VSS94  = GND
  CK_T  = M_D_CPU0_CLK_DP<1>
  CK_C  = M_D_CPU0_CLK_DN<1>
  VSS95  = GND
  RFU4  = TP_CHD_CPU0_DIMM2_FRU_4
  CA1_B  = M_D_CPU0_SB_CA<1>
  VSS96  = GND
  CA3_B  = M_D_CPU0_SB_CA<3>
  VSS97  = GND
  CA5_B  = M_D_CPU0_SB_CA<5>
  VSS98  = GND
  PAR_B  = M_D_CPU0_SB_PAR
  VSS99  = GND
  CS1_B_N  = M_D_CPU0_SB_CS_N<3>
  VSS100  = GND
  RFU5  = TP_CHD_CPU0_DIMM2_FRU_5
  RFU6  = TP_CHD_CPU0_DIMM2_FRU_6
  VSS101  = GND
  CB6_B  = M_D_CPU0_SB_CB<6>
  VSS102  = GND
  CB7_B  = M_D_CPU0_SB_CB<7>
  VSS103  = GND
  DQS4_B_C  = M_D_CPU0_SB_DQS_DN<4>
  DQS4_B_T  = M_D_CPU0_SB_DQS_DP<4>
  VSS104  = GND
  CB2_B  = M_D_CPU0_SB_CB<2>
  VSS105  = GND
  CB3_B  = M_D_CPU0_SB_CB<3>
  VSS106  = GND
  DQ2_B  = M_D_CPU0_SB_DQ<2>
  VSS107  = GND
  DQ3_B  = M_D_CPU0_SB_DQ<3>
  VSS108  = GND
  \dqs5_b_c||tdqs5_b_c\  = M_D_CPU0_SB_DQS_DN<5>
  \dqs5_b_t||tdqs5_b_t\  = M_D_CPU0_SB_DQS_DP<5>
  VSS109  = GND
  DQ6_B  = M_D_CPU0_SB_DQ<6>
  VSS110  = GND
  DQ7_B  = M_D_CPU0_SB_DQ<7>
  VSS111  = GND
  DQ10_B  = M_D_CPU0_SB_DQ<10>
  VSS112  = GND
  DQ11_B  = M_D_CPU0_SB_DQ<11>
  VSS113  = GND
  \dqs6_b_c||tdqs6_b_c\  = M_D_CPU0_SB_DQS_DN<6>
  \dqs6_b_t||tdqs6_b_t\  = M_D_CPU0_SB_DQS_DP<6>
  VSS114  = GND
  DQ14_B  = M_D_CPU0_SB_DQ<14>
  VSS115  = GND
  DQ15_B  = M_D_CPU0_SB_DQ<15>
  VSS116  = GND
  DQ18_B  = M_D_CPU0_SB_DQ<18>
  VSS117  = GND
  DQ19_B  = M_D_CPU0_SB_DQ<19>
  VSS118  = GND
  \dqs7_b_c||tdqs7_b_c\  = M_D_CPU0_SB_DQS_DN<7>
  \dqs7_b_t||tdqs7_b_t\  = M_D_CPU0_SB_DQS_DP<7>
  VSS119  = GND
  DQ22_B  = M_D_CPU0_SB_DQ<22>
  VSS120  = GND
  DQ23_B  = M_D_CPU0_SB_DQ<23>
  VSS121  = GND
  DQ26_B  = M_D_CPU0_SB_DQ<26>
  VSS122  = GND
  DQ27_B  = M_D_CPU0_SB_DQ<27>
  VSS123  = GND
  \dqs8_b_c||tdqs8_b_c\  = M_D_CPU0_SB_DQS_DN<8>
  \dqs8_b_t||tdqs8_b_t\  = M_D_CPU0_SB_DQS_DP<8>
  VSS124  = GND
  DQ30_B  = M_D_CPU0_SB_DQ<30>
  VSS125  = GND
  DQ31_B  = M_D_CPU0_SB_DQ<31>
  VSS126  = GND
  G1  = GND
  G2  = GND
  G3  = GND

(kicad_pcb
	(version 20260206)
	(generator "pcbnew")
	(generator_version "10.0")
	(general
		(thickness 1.6)
		(legacy_teardrops no)
	)
	(paper "A4")
	(title_block
		(title "03242023_DA0F0TMBIJ0_F0T_Motherboard_J_brd_V01_OCP.brd")
		(comment 1 "Grand Teton / footprint 652 of 6105 (J8), pads 92-137 of 291")
	)
	(layers
		(0 "F.Cu" signal "TOP")
		(4 "In1.Cu" signal "GND")
		(6 "In2.Cu" signal "IN1")
		(8 "In3.Cu" signal "GND1")
		(10 "In4.Cu" signal "IN2")
		(12 "In5.Cu" signal "GND2")
		(14 "In6.Cu" signal "IN3")
		(16 "In7.Cu" signal "GND3")
		(18 "In8.Cu" signal "VCC")
		(20 "In9.Cu" signal "VCC1")
		(22 "In10.Cu" signal "GND4")
		(24 "In11.Cu" signal "IN4")
		(26 "In12.Cu" signal "GND5")
		(28 "In13.Cu" signal "IN5")
		(30 "In14.Cu" signal "GND6")
		(32 "In15.Cu" signal "IN6")
		(34 "In16.Cu" signal "GND7")
		(2 "B.Cu" signal "BOTTOM")
		(9 "F.Adhes" user "F.Adhesive")
		(11 "B.Adhes" user "B.Adhesive")
		(13 "F.Paste" user "Package Geometry/Pastemask Top")
		(15 "B.Paste" user "Package Geometry/Pastemask Bottom")
		(5 "F.SilkS" user "Ref Des/Silkscreen Top")
		(7 "B.SilkS" user "Ref Des/Silkscreen Bottom")
		(1 "F.Mask" user "Board Geometry/Soldermask Top")
		(3 "B.Mask" user "Board Geometry/Soldermask Bottom")
		(17 "Dwgs.User" user "User.Drawings")
		(19 "Cmts.User" user "User.Comments")
		(21 "Eco1.User" user "User.Eco1")
		(23 "Eco2.User" user "User.Eco2")
		(25 "Edge.Cuts" user "Board Geometry/Outline")
		(27 "Margin" user)
		(31 "F.CrtYd" user "Package Geometry/Place Bound Top")
		(29 "B.CrtYd" user "Package Geometry/Place Bound Bottom")
		(35 "F.Fab" user "Ref Des/Assembly Top")
		(33 "B.Fab" user "Ref Des/Assembly Bottom")
	)
	(footprint ""
		(layer "F.Cu")
		(at 265.674348 -258.091686)
		(property "Reference" "J8"
			(at -3.683 -81.702148 0)
			(unlocked yes)
			(layer "F.SilkS")
			(effects
				(font
					(size 0.7874 0.5842)
					(thickness 0.1524)
				)
				(justify left)
			)
		)
		(property "Value" ""
			(at 0 0 0)
			(layer "F.Fab")
			(effects
				(font
					(size 1.27 1.27)
				)
			)
		)
		(duplicate_pad_numbers_are_jumpers no)
		(pad "92" smd rect
			(at -2.050034 19.12493 270)
			(size 0.519938 1.4986)
			(layers "F.Cu" "F.Mask" "F.Paste")
			(net "GND")
		)
		(pad "93" smd rect
			(at -2.050034 19.975068 270)
			(size 0.519938 1.4986)
			(layers "F.Cu" "F.Mask" "F.Paste")
			(net "M_D_CPU0_SB_DQS_DP<9>")
		)
		(pad "94" smd rect
			(at -2.050034 20.824952 270)
			(size 0.519938 1.4986)
			(layers "F.Cu" "F.Mask" "F.Paste")
			(net "M_D_CPU0_SB_DQS_DN<9>")
		)
		(pad "95" smd rect
			(at -2.050034 21.67509 270)
			(size 0.519938 1.4986)
			(layers "F.Cu" "F.Mask" "F.Paste")
			(net "GND")
		)
		(pad "96" smd rect
			(at -2.050034 22.524974 270)
			(size 0.519938 1.4986)
			(layers "F.Cu" "F.Mask" "F.Paste")
			(net "M_D_CPU0_SB_CB<0>")
		)
		(pad "97" smd rect
			(at -2.050034 23.375112 270)
			(size 0.519938 1.4986)
			(layers "F.Cu" "F.Mask" "F.Paste")
			(net "GND")
		)
		(pad "98" smd rect
			(at -2.050034 24.224996 270)
			(size 0.519938 1.4986)
			(layers "F.Cu" "F.Mask" "F.Paste")
			(net "M_D_CPU0_SB_CB<1>")
		)
		(pad "99" smd rect
			(at -2.050034 25.07488 270)
			(size 0.519938 1.4986)
			(layers "F.Cu" "F.Mask" "F.Paste")
			(net "GND")
		)
		(pad "100" smd rect
			(at -2.050034 25.925018 270)
			(size 0.519938 1.4986)
			(layers "F.Cu" "F.Mask" "F.Paste")
			(net "M_D_CPU0_SB_DQ<0>")
		)
		(pad "101" smd rect
			(at -2.050034 26.774902 270)
			(size 0.519938 1.4986)
			(layers "F.Cu" "F.Mask" "F.Paste")
			(net "GND")
		)
		(pad "102" smd rect
			(at -2.050034 27.62504 270)
			(size 0.519938 1.4986)
			(layers "F.Cu" "F.Mask" "F.Paste")
			(net "M_D_CPU0_SB_DQ<1>")
		)
		(pad "103" smd rect
			(at -2.050034 28.474924 270)
			(size 0.519938 1.4986)
			(layers "F.Cu" "F.Mask" "F.Paste")
			(net "GND")
		)
		(pad "104" smd rect
			(at -2.050034 29.325062 270)
			(size 0.519938 1.4986)
			(layers "F.Cu" "F.Mask" "F.Paste")
			(net "M_D_CPU0_SB_DQS_DP<0>")
		)
		(pad "105" smd rect
			(at -2.050034 30.174946 270)
			(size 0.519938 1.4986)
			(layers "F.Cu" "F.Mask" "F.Paste")
			(net "M_D_CPU0_SB_DQS_DN<0>")
		)
		(pad "106" smd rect
			(at -2.050034 31.025084 270)
			(size 0.519938 1.4986)
			(layers "F.Cu" "F.Mask" "F.Paste")
			(net "GND")
		)
		(pad "107" smd rect
			(at -2.050034 31.874968 270)
			(size 0.519938 1.4986)
			(layers "F.Cu" "F.Mask" "F.Paste")
			(net "M_D_CPU0_SB_DQ<4>")
		)
		(pad "108" smd rect
			(at -2.050034 32.725106 270)
			(size 0.519938 1.4986)
			(layers "F.Cu" "F.Mask" "F.Paste")
			(net "GND")
		)
		(pad "109" smd rect
			(at -2.050034 33.57499 270)
			(size 0.519938 1.4986)
			(layers "F.Cu" "F.Mask" "F.Paste")
			(net "M_D_CPU0_SB_DQ<5>")
		)
		(pad "110" smd rect
			(at -2.050034 34.425128 270)
			(size 0.519938 1.4986)
			(layers "F.Cu" "F.Mask" "F.Paste")
			(net "GND")
		)
		(pad "111" smd rect
			(at -2.050034 35.275012 270)
			(size 0.519938 1.4986)
			(layers "F.Cu" "F.Mask" "F.Paste")
			(net "M_D_CPU0_SB_DQ<8>")
		)
		(pad "112" smd rect
			(at -2.050034 36.124896 270)
			(size 0.519938 1.4986)
			(layers "F.Cu" "F.Mask" "F.Paste")
			(net "GND")
		)
		(pad "113" smd rect
			(at -2.050034 36.975034 270)
			(size 0.519938 1.4986)
			(layers "F.Cu" "F.Mask" "F.Paste")
			(net "M_D_CPU0_SB_DQ<9>")
		)
		(pad "114" smd rect
			(at -2.050034 37.824918 270)
			(size 0.519938 1.4986)
			(layers "F.Cu" "F.Mask" "F.Paste")
			(net "GND")
		)
		(pad "115" smd rect
			(at -2.050034 38.675056 270)
			(size 0.519938 1.4986)
			(layers "F.Cu" "F.Mask" "F.Paste")
			(net "M_D_CPU0_SB_DQS_DP<1>")
		)
		(pad "116" smd rect
			(at -2.050034 39.52494 270)
			(size 0.519938 1.4986)
			(layers "F.Cu" "F.Mask" "F.Paste")
			(net "M_D_CPU0_SB_DQS_DN<1>")
		)
		(pad "117" smd rect
			(at -2.050034 40.375078 270)
			(size 0.519938 1.4986)
			(layers "F.Cu" "F.Mask" "F.Paste")
			(net "GND")
		)
		(pad "118" smd rect
			(at -2.050034 41.224962 270)
			(size 0.519938 1.4986)
			(layers "F.Cu" "F.Mask" "F.Paste")
			(net "M_D_CPU0_SB_DQ<12>")
		)
		(pad "119" smd rect
			(at -2.050034 42.0751 270)
			(size 0.519938 1.4986)
			(layers "F.Cu" "F.Mask" "F.Paste")
			(net "GND")
		)
		(pad "120" smd rect
			(at -2.050034 42.924984 270)
			(size 0.519938 1.4986)
			(layers "F.Cu" "F.Mask" "F.Paste")
			(net "M_D_CPU0_SB_DQ<13>")
		)
		(pad "121" smd rect
			(at -2.050034 43.775122 270)
			(size 0.519938 1.4986)
			(layers "F.Cu" "F.Mask" "F.Paste")
			(net "GND")
		)
		(pad "122" smd rect
			(at -2.050034 44.625006 270)
			(size 0.519938 1.4986)
			(layers "F.Cu" "F.Mask" "F.Paste")
			(net "M_D_CPU0_SB_DQ<16>")
		)
		(pad "123" smd rect
			(at -2.050034 45.47489 270)
			(size 0.519938 1.4986)
			(layers "F.Cu" "F.Mask" "F.Paste")
			(net "GND")
		)
		(pad "124" smd rect
			(at -2.050034 46.325028 270)
			(size 0.519938 1.4986)
			(layers "F.Cu" "F.Mask" "F.Paste")
			(net "M_D_CPU0_SB_DQ<17>")
		)
		(pad "125" smd rect
			(at -2.050034 47.174912 270)
			(size 0.519938 1.4986)
			(layers "F.Cu" "F.Mask" "F.Paste")
			(net "GND")
		)
		(pad "126" smd rect
			(at -2.050034 48.02505 270)
			(size 0.519938 1.4986)
			(layers "F.Cu" "F.Mask" "F.Paste")
			(net "M_D_CPU0_SB_DQS_DP<2>")
		)
		(pad "127" smd rect
			(at -2.050034 48.874934 270)
			(size 0.519938 1.4986)
			(layers "F.Cu" "F.Mask" "F.Paste")
			(net "M_D_CPU0_SB_DQS_DN<2>")
		)
		(pad "128" smd rect
			(at -2.050034 49.725072 270)
			(size 0.519938 1.4986)
			(layers "F.Cu" "F.Mask" "F.Paste")
			(net "GND")
		)
		(pad "129" smd rect
			(at -2.050034 50.574956 270)
			(size 0.519938 1.4986)
			(layers "F.Cu" "F.Mask" "F.Paste")
			(net "M_D_CPU0_SB_DQ<20>")
		)
		(pad "130" smd rect
			(at -2.050034 51.425094 270)
			(size 0.519938 1.4986)
			(layers "F.Cu" "F.Mask" "F.Paste")
			(net "GND")
		)
		(pad "131" smd rect
			(at -2.050034 52.274978 270)
			(size 0.519938 1.4986)
			(layers "F.Cu" "F.Mask" "F.Paste")
			(net "M_D_CPU0_SB_DQ<21>")
		)
		(pad "132" smd rect
			(at -2.050034 53.125116 270)
			(size 0.519938 1.4986)
			(layers "F.Cu" "F.Mask" "F.Paste")
			(net "GND")
		)
		(pad "133" smd rect
			(at -2.050034 53.975 270)
			(size 0.519938 1.4986)
			(layers "F.Cu" "F.Mask" "F.Paste")
			(net "M_D_CPU0_SB_DQ<24>")
		)
		(pad "134" smd rect
			(at -2.050034 54.824884 270)
			(size 0.519938 1.4986)
			(layers "F.Cu" "F.Mask" "F.Paste")
			(net "GND")
		)
		(pad "135" smd rect
			(at -2.050034 55.675022 270)
			(size 0.519938 1.4986)
			(layers "F.Cu" "F.Mask" "F.Paste")
			(net "M_D_CPU0_SB_DQ<25>")
		)
		(pad "136" smd rect
			(at -2.050034 56.524906 270)
			(size 0.519938 1.4986)
			(layers "F.Cu" "F.Mask" "F.Paste")
			(net "GND")
		)
		(pad "137" smd rect
			(at -2.050034 57.375044 270)
			(size 0.519938 1.4986)
			(layers "F.Cu" "F.Mask" "F.Paste")
			(net "M_D_CPU0_SB_DQS_DP<3>")
		)
	)
)
